(kicad_pcb
	(version 20260206)
	(generator "pcbnew")
	(generator_version "10.0")
	(general
		(thickness 1.6)
		(legacy_teardrops no)
	)
	(paper "A4")
	(title_block
		(title "04192023_DAF0TMB3IC0_F0TG_MB_C_brd_V02_OCP.brd")
		(comment 1 "Grand Teton / footprints 3833-3837 of 8354")
	)
	(layers
		(0 "F.Cu" signal "TOP")
		(4 "In1.Cu" signal "GND")
		(6 "In2.Cu" signal "IN1")
		(8 "In3.Cu" signal "GND1")
		(10 "In4.Cu" signal "IN2")
		(12 "In5.Cu" signal "GND2")
		(14 "In6.Cu" signal "IN3")
		(16 "In7.Cu" signal "GND3")
		(18 "In8.Cu" signal "VCC")
		(20 "In9.Cu" signal "VCC1")
		(22 "In10.Cu" signal "GND4")
		(24 "In11.Cu" signal "IN4")
		(26 "In12.Cu" signal "GND5")
		(28 "In13.Cu" signal "IN5")
		(30 "In14.Cu" signal "GND6")
		(32 "In15.Cu" signal "IN6")
		(34 "In16.Cu" signal "GND7")
		(2 "B.Cu" signal "BOTTOM")
		(9 "F.Adhes" user "F.Adhesive")
		(11 "B.Adhes" user "B.Adhesive")
		(13 "F.Paste" user "Package Geometry/Pastemask Top")
		(15 "B.Paste" user "Package Geometry/Pastemask Bottom")
		(5 "F.SilkS" user "Ref Des/Silkscreen Top")
		(7 "B.SilkS" user "Ref Des/Silkscreen Bottom")
		(1 "F.Mask" user "Board Geometry/Soldermask Top")
		(3 "B.Mask" user "Board Geometry/Soldermask Bottom")
		(17 "Dwgs.User" user "User.Drawings")
		(19 "Cmts.User" user "User.Comments")
		(21 "Eco1.User" user "User.Eco1")
		(23 "Eco2.User" user "User.Eco2")
		(25 "Edge.Cuts" user "Board Geometry/Outline")
		(27 "Margin" user)
		(31 "F.CrtYd" user "Package Geometry/Place Bound Top")
		(29 "B.CrtYd" user "Package Geometry/Place Bound Bottom")
		(35 "F.Fab" user "Ref Des/Assembly Top")
		(33 "B.Fab" user "Ref Des/Assembly Bottom")
	)
	(footprint ""
		(layer "F.Cu")
		(at 318.34582 -334.995266)
		(property "Reference" "PU15"
			(at 3.34518 -7.624064 0)
			(unlocked yes)
			(layer "F.SilkS")
			(effects
				(font
					(size 0.7874 0.5842)
					(thickness 0.1524)
				)
				(justify left)
			)
		)
		(property "Value" ""
			(at 0 0 0)
			(layer "F.Fab")
			(effects
				(font
					(size 1.27 1.27)
				)
			)
		)
		(duplicate_pad_numbers_are_jumpers no)
		(fp_line
			(start -2.500122 -2.999994)
			(end -2.24409 -2.999994)
			(stroke
				(width 0.1524)
				(type default)
			)
			(layer "F.SilkS")
		)
		(fp_line
			(start -2.500122 -2.529078)
			(end -2.500122 -2.999994)
			(stroke
				(width 0.1524)
				(type default)
			)
			(layer "F.SilkS")
		)
		(fp_line
			(start -2.500122 0.6604)
			(end -2.500122 0.229108)
			(stroke
				(width 0.1524)
				(type default)
			)
			(layer "F.SilkS")
		)
		(fp_line
			(start -2.500122 2.999994)
			(end -2.500122 2.339594)
			(stroke
				(width 0.1524)
				(type default)
			)
			(layer "F.SilkS")
		)
		(fp_line
			(start -2.2987 2.999994)
			(end -2.500122 2.999994)
			(stroke
				(width 0.1524)
				(type default)
			)
			(layer "F.SilkS")
		)
		(fp_line
			(start 2.31394 -2.999994)
			(end 2.500122 -2.999994)
			(stroke
				(width 0.1524)
				(type default)
			)
			(layer "F.SilkS")
		)
		(fp_line
			(start 2.500122 -2.999994)
			(end 2.500122 -2.44348)
			(stroke
				(width 0.1524)
				(type default)
			)
			(layer "F.SilkS")
		)
		(fp_line
			(start 2.500122 2.339594)
			(end 2.500122 2.999994)
			(stroke
				(width 0.1524)
				(type default)
			)
			(layer "F.SilkS")
		)
		(fp_line
			(start 2.500122 2.999994)
			(end 2.2987 2.999994)
			(stroke
				(width 0.1524)
				(type default)
			)
			(layer "F.SilkS")
		)
		(fp_poly
			(pts
				(xy -2.780792 -2.420112) (xy -3.4544 -2.644648) (xy -3.005328 -3.09372)
			)
			(stroke
				(width 0)
				(type default)
			)
			(fill yes)
			(layer "F.SilkS")
		)
		(fp_line
			(start -2.500122 -2.999994)
			(end 2.500122 -2.999994)
			(stroke
				(width 0.1)
				(type default)
			)
			(layer "F.Fab")
		)
		(fp_line
			(start -2.500122 2.999994)
			(end -2.500122 -2.999994)
			(stroke
				(width 0.1)
				(type default)
			)
			(layer "F.Fab")
		)
		(fp_line
			(start 2.500122 -2.999994)
			(end 2.500122 2.999994)
			(stroke
				(width 0.1)
				(type default)
			)
			(layer "F.Fab")
		)
		(fp_line
			(start 2.500122 2.999994)
			(end -2.500122 2.999994)
			(stroke
				(width 0.1)
				(type default)
			)
			(layer "F.Fab")
		)
		(fp_poly
			(pts
				(xy -4.218432 -2.783078) (xy -4.218432 -1.767078) (xy -3.202432 -2.275078)
			)
			(stroke
				(width 0)
				(type default)
			)
			(fill yes)
			(layer "F.Fab")
		)
		(pad "1" smd rect
			(at -2.400046 -2.275078 90)
			(size 0.2286 0.6096)
			(layers "F.Cu" "F.Mask" "F.Paste")
			(net "PVDDCR_CPU1_P0_VOS3")
		)
		(pad "2" smd rect
			(at -2.400046 -1.82499 90)
			(size 0.2286 0.6096)
			(layers "F.Cu" "F.Mask" "F.Paste")
			(net "GND")
		)
		(pad "3" smd rect
			(at -2.400046 -1.374902 90)
			(size 0.2286 0.6096)
			(layers "F.Cu" "F.Mask" "F.Paste")
			(net "PVDDCR_CPU1_P0_VCC3")
		)
		(pad "4" smd rect
			(at -2.400046 -0.925068 90)
			(size 0.2286 0.6096)
			(layers "F.Cu" "F.Mask" "F.Paste")
			(net "PVDDCR_CPU1_P0_PVCC")
		)
		(pad "5" smd rect
			(at -2.400046 -0.47498 90)
			(size 0.2286 0.6096)
			(layers "F.Cu" "F.Mask" "F.Paste")
			(net "GND")
		)
		(pad "6" smd rect
			(at -2.400046 -0.024892 90)
			(size 0.2286 0.6096)
			(layers "F.Cu" "F.Mask" "F.Paste")
			(net "NC_PVDDCR_CPU1_P0_GL1_3")
		)
		(pad "7_9-20_24" smd circle
			(at 0 1.150112 90)
			(size 0 0)
			(layers "F.Cu" "F.Mask" "F.Paste")
			(net "GND")
		)
		(pad "10_19" smd rect
			(at 0 2.899918 90)
			(size 0.6096 4.318)
			(layers "F.Cu" "F.Mask" "F.Paste")
			(net "SW_PVDDCR_CPU1_P0_SW3")
		)
		(pad "25_29" smd rect
			(at 1.549908 -1.279906 270)
			(size 2.0574 2.3114)
			(layers "F.Cu" "F.Mask" "F.Paste")
			(net "SW_P12V_AUX_PVDDCR_CPU1_P0_FLT")
		)
		(pad "30" smd rect
			(at 2.05994 -2.899918)
			(size 0.2286 0.6096)
			(layers "F.Cu" "F.Mask" "F.Paste")
			(net "SW_P12V_AUX_PVDDCR_CPU1_P0_FLT")
		)
		(pad "31" smd rect
			(at 1.610106 -2.899918)
			(size 0.2286 0.6096)
			(layers "F.Cu" "F.Mask" "F.Paste")
			(net "NC_PVDDCR_CPU1_P0_DNC3")
		)
		(pad "32" smd rect
			(at 1.160018 -2.899918)
			(size 0.2286 0.6096)
			(layers "F.Cu" "F.Mask" "F.Paste")
			(net "SW_PVDDCR_CPU1_P0_BOOTR3")
		)
		(pad "33" smd rect
			(at 0.70993 -2.899918)
			(size 0.2286 0.6096)
			(layers "F.Cu" "F.Mask" "F.Paste")
			(net "SW_PVDDCR_CPU1_P0_BOOT3")
		)
		(pad "34" smd rect
			(at 0.260096 -2.899918)
			(size 0.2286 0.6096)
			(layers "F.Cu" "F.Mask" "F.Paste")
			(net "PVDDCR_CPU1_P0_PWM3")
		)
		(pad "35" smd rect
			(at -0.189992 -2.899918)
			(size 0.2286 0.6096)
			(layers "F.Cu" "F.Mask" "F.Paste")
			(net "PVDDCR_CPU1_P0_VCC3")
		)
		(pad "36" smd rect
			(at -0.64008 -2.899918)
			(size 0.2286 0.6096)
			(layers "F.Cu" "F.Mask" "F.Paste")
			(net "PVDDCR_CPU1_P0_TEMP0")
		)
		(pad "37" smd rect
			(at -1.089914 -2.899918)
			(size 0.2286 0.6096)
			(layers "F.Cu" "F.Mask" "F.Paste")
			(net "PVDDCR_CPU1_P0_LSET3")
		)
		(pad "38" smd rect
			(at -1.540002 -2.899918)
			(size 0.2286 0.6096)
			(layers "F.Cu" "F.Mask" "F.Paste")
			(net "PVDDCR_CPU1_P0_IMON3")
		)
		(pad "39" smd rect
			(at -1.99009 -2.899918)
			(size 0.2286 0.6096)
			(layers "F.Cu" "F.Mask" "F.Paste")
			(net "PVDDCR_CPU1_P0_VCCS")
		)
		(pad "40" smd rect
			(at -0.87503 -1.27508)
			(size 1.7526 1.9558)
			(layers "F.Cu" "F.Mask" "F.Paste")
			(net "GND")
		)
		(pad "41" smd rect
			(at -1.525016 0.249936 270)
			(size 0.3048 0.4572)
			(layers "F.Cu" "F.Mask" "F.Paste")
			(net "NC_PVDDCR_CPU1_P0_GL2_3")
		)
		(zone
			(layer "F.Cu")
			(hatch none 0.5)
			(connect_pads
				(clearance 0)
			)
			(min_thickness 0.25)
			(keepout
				(tracks not_allowed)
				(vias allowed)
				(pads allowed)
				(copperpour not_allowed)
				(footprints allowed)
			)
			(placement
				(enabled no)
				(sheetname "")
			)
			(fill
				(thermal_gap 0.5)
				(thermal_bridge_width 0.5)
				(island_removal_mode 0)
			)
			(polygon
				(pts
					(xy 315.845698 -332.417674) (xy 315.845698 -332.744572) (xy 320.845942 -332.744572) (xy 320.845942 -332.418436)
					(xy 320.55562 -332.418436) (xy 320.55562 -332.450948) (xy 316.13602 -332.450948) (xy 316.13602 -332.417674)
				)
			)
		)
		(zone
			(layer "F.Cu")
			(hatch none 0.5)
			(connect_pads
				(clearance 0)
			)
			(min_thickness 0.25)
			(keepout
				(tracks not_allowed)
				(vias allowed)
				(pads allowed)
				(copperpour not_allowed)
				(footprints allowed)
			)
			(placement
				(enabled no)
				(sheetname "")
			)
			(fill
				(thermal_gap 0.5)
				(thermal_bridge_width 0.5)
				(island_removal_mode 0)
			)
			(polygon
				(pts
					(xy 318.39789 -335.241646) (xy 318.39789 -337.299046) (xy 316.54369 -337.299046) (xy 316.54369 -337.058)
					(xy 316.301374 -337.058) (xy 316.301374 -337.539584) (xy 320.226182 -337.539584) (xy 320.226182 -337.354672)
					(xy 318.689228 -337.354672) (xy 318.689228 -335.195672) (xy 320.845942 -335.195672) (xy 320.845942 -334.94599)
					(xy 318.693546 -334.94599)
				)
			)
		)
	)
	(footprint ""
		(layer "F.Cu")
		(at 96.715834 -136.052052 -90)
		(property "Reference" "R6087"
			(at 0 0 270)
			(layer "F.SilkS")
			(hide yes)
			(effects
				(font
					(size 1.27 1.27)
				)
			)
		)
		(property "Value" ""
			(at 0 0 270)
			(layer "F.Fab")
			(effects
				(font
					(size 1.27 1.27)
				)
			)
		)
		(duplicate_pad_numbers_are_jumpers no)
		(fp_line
			(start -0.7874 0.4064)
			(end -0.7874 -0.4064)
			(stroke
				(width 0.1524)
				(type default)
			)
			(layer "F.SilkS")
		)
		(fp_line
			(start 0.7874 0.4064)
			(end -0.7874 0.4064)
			(stroke
				(width 0.1524)
				(type default)
			)
			(layer "F.SilkS")
		)
		(fp_line
			(start -0.7874 -0.4064)
			(end 0.7874 -0.4064)
			(stroke
				(width 0.1524)
				(type default)
			)
			(layer "F.SilkS")
		)
		(fp_line
			(start 0.7874 -0.4064)
			(end 0.7874 0.4064)
			(stroke
				(width 0.1524)
				(type default)
			)
			(layer "F.SilkS")
		)
		(fp_line
			(start -0.67945 0.3048)
			(end -0.67945 -0.305054)
			(stroke
				(width 0.1)
				(type default)
			)
			(layer "F.Fab")
		)
		(fp_line
			(start -0.12065 0.3048)
			(end -0.67945 0.3048)
			(stroke
				(width 0.1)
				(type default)
			)
			(layer "F.Fab")
		)
		(fp_line
			(start 0.120396 0.3048)
			(end 0.120396 0.2794)
			(stroke
				(width 0.1)
				(type default)
			)
			(layer "F.Fab")
		)
		(fp_line
			(start 0.67945 0.3048)
			(end 0.120396 0.3048)
			(stroke
				(width 0.1)
				(type default)
			)
			(layer "F.Fab")
		)
		(fp_line
			(start -0.12065 0.2794)
			(end -0.12065 0.3048)
			(stroke
				(width 0.1)
				(type default)
			)
			(layer "F.Fab")
		)
		(fp_line
			(start 0.120396 0.2794)
			(end -0.12065 0.2794)
			(stroke
				(width 0.1)
				(type default)
			)
			(layer "F.Fab")
		)
		(fp_line
			(start -0.12065 -0.2794)
			(end 0.12065 -0.2794)
			(stroke
				(width 0.1)
				(type default)
			)
			(layer "F.Fab")
		)
		(fp_line
			(start 0.12065 -0.2794)
			(end 0.12065 -0.3048)
			(stroke
				(width 0.1)
				(type default)
			)
			(layer "F.Fab")
		)
		(fp_line
			(start 0.12065 -0.3048)
			(end 0.67945 -0.3048)
			(stroke
				(width 0.1)
				(type default)
			)
			(layer "F.Fab")
		)
		(fp_line
			(start 0.67945 -0.3048)
			(end 0.67945 0.3048)
			(stroke
				(width 0.1)
				(type default)
			)
			(layer "F.Fab")
		)
		(fp_line
			(start -0.67945 -0.305054)
			(end -0.12065 -0.305054)
			(stroke
				(width 0.1)
				(type default)
			)
			(layer "F.Fab")
		)
		(fp_line
			(start -0.12065 -0.305054)
			(end -0.12065 -0.2794)
			(stroke
				(width 0.1)
				(type default)
			)
			(layer "F.Fab")
		)
		(pad "1" smd circle
			(at -0.40005 0 270)
			(size 0 0)
			(layers "F.Cu" "F.Mask" "F.Paste")
			(net "PVDDCR_SOC_P1_EN_RC")
		)
		(pad "2" smd circle
			(at 0.40005 0 270)
			(size 0 0)
			(layers "F.Cu" "F.Mask" "F.Paste")
			(net "GND")
		)
	)
	(footprint ""
		(layer "F.Cu")
		(at 439.276744 -428.92091 -90)
		(property "Reference" "R650"
			(at 0 0 270)
			(layer "F.SilkS")
			(hide yes)
			(effects
				(font
					(size 1.27 1.27)
				)
			)
		)
		(property "Value" ""
			(at 0 0 270)
			(layer "F.Fab")
			(effects
				(font
					(size 1.27 1.27)
				)
			)
		)
		(duplicate_pad_numbers_are_jumpers no)
		(fp_line
			(start -0.7874 0.4064)
			(end -0.7874 -0.4064)
			(stroke
				(width 0.1524)
				(type default)
			)
			(layer "F.SilkS")
		)
		(fp_line
			(start 0.7874 0.4064)
			(end -0.7874 0.4064)
			(stroke
				(width 0.1524)
				(type default)
			)
			(layer "F.SilkS")
		)
		(fp_line
			(start -0.7874 -0.4064)
			(end 0.7874 -0.4064)
			(stroke
				(width 0.1524)
				(type default)
			)
			(layer "F.SilkS")
		)
		(fp_line
			(start 0.7874 -0.4064)
			(end 0.7874 0.4064)
			(stroke
				(width 0.1524)
				(type default)
			)
			(layer "F.SilkS")
		)
		(fp_line
			(start -0.67945 0.3048)
			(end -0.67945 -0.305054)
			(stroke
				(width 0.1)
				(type default)
			)
			(layer "F.Fab")
		)
		(fp_line
			(start -0.12065 0.3048)
			(end -0.67945 0.3048)
			(stroke
				(width 0.1)
				(type default)
			)
			(layer "F.Fab")
		)
		(fp_line
			(start 0.120396 0.3048)
			(end 0.120396 0.2794)
			(stroke
				(width 0.1)
				(type default)
			)
			(layer "F.Fab")
		)
		(fp_line
			(start 0.67945 0.3048)
			(end 0.120396 0.3048)
			(stroke
				(width 0.1)
				(type default)
			)
			(layer "F.Fab")
		)
		(fp_line
			(start -0.12065 0.2794)
			(end -0.12065 0.3048)
			(stroke
				(width 0.1)
				(type default)
			)
			(layer "F.Fab")
		)
		(fp_line
			(start 0.120396 0.2794)
			(end -0.12065 0.2794)
			(stroke
				(width 0.1)
				(type default)
			)
			(layer "F.Fab")
		)
		(fp_line
			(start -0.12065 -0.2794)
			(end 0.12065 -0.2794)
			(stroke
				(width 0.1)
				(type default)
			)
			(layer "F.Fab")
		)
		(fp_line
			(start 0.12065 -0.2794)
			(end 0.12065 -0.3048)
			(stroke
				(width 0.1)
				(type default)
			)
			(layer "F.Fab")
		)
		(fp_line
			(start 0.12065 -0.3048)
			(end 0.67945 -0.3048)
			(stroke
				(width 0.1)
				(type default)
			)
			(layer "F.Fab")
		)
		(fp_line
			(start 0.67945 -0.3048)
			(end 0.67945 0.3048)
			(stroke
				(width 0.1)
				(type default)
			)
			(layer "F.Fab")
		)
		(fp_line
			(start -0.67945 -0.305054)
			(end -0.12065 -0.305054)
			(stroke
				(width 0.1)
				(type default)
			)
			(layer "F.Fab")
		)
		(fp_line
			(start -0.12065 -0.305054)
			(end -0.12065 -0.2794)
			(stroke
				(width 0.1)
				(type default)
			)
			(layer "F.Fab")
		)
		(pad "1" smd circle
			(at -0.40005 0 270)
			(size 0 0)
			(layers "F.Cu" "F.Mask" "F.Paste")
			(net "PWRGD_P0V9_RETIMER_CPU0")
		)
		(pad "2" smd circle
			(at 0.40005 0 270)
			(size 0 0)
			(layers "F.Cu" "F.Mask" "F.Paste")
			(net "PWRGD_P0V9_RETIMER_CPU0_R")
		)
	)
	(footprint ""
		(layer "F.Cu")
		(at 81.464404 -408.517344 -90)
		(property "Reference" "C6652"
			(at 0 0 270)
			(layer "F.SilkS")
			(hide yes)
			(effects
				(font
					(size 1.27 1.27)
				)
			)
		)
		(property "Value" ""
			(at 0 0 270)
			(layer "F.Fab")
			(effects
				(font
					(size 1.27 1.27)
				)
			)
		)
		(duplicate_pad_numbers_are_jumpers no)
		(fp_line
			(start -0.299974 0.150114)
			(end -0.299974 -0.150114)
			(stroke
				(width 0.1)
				(type default)
			)
			(layer "F.Fab")
		)
		(fp_line
			(start 0.299974 0.150114)
			(end -0.299974 0.150114)
			(stroke
				(width 0.1)
				(type default)
			)
			(layer "F.Fab")
		)
		(fp_line
			(start -0.299974 -0.150114)
			(end 0.299974 -0.150114)
			(stroke
				(width 0.1)
				(type default)
			)
			(layer "F.Fab")
		)
		(fp_line
			(start 0.299974 -0.150114)
			(end 0.299974 0.150114)
			(stroke
				(width 0.1)
				(type default)
			)
			(layer "F.Fab")
		)
		(pad "1" smd rect
			(at -0.2667 0 270)
			(size 0.3048 0.381)
			(layers "F.Cu" "F.Mask" "F.Paste")
			(net "P5E_CPU1_P0_TX_BUF_C_DN<11>")
		)
		(pad "2" smd rect
			(at 0.2667 0 270)
			(size 0.3048 0.381)
			(layers "F.Cu" "F.Mask" "F.Paste")
			(net "P5E_CPU1_P0_TX_BUF_DN<11>")
		)
	)
	(footprint ""
		(layer "F.Cu")
		(at 60.936124 -408.517344 -90)
		(property "Reference" "C6637"
			(at 0 0 270)
			(layer "F.SilkS")
			(hide yes)
			(effects
				(font
					(size 1.27 1.27)
				)
			)
		)
		(property "Value" ""
			(at 0 0 270)
			(layer "F.Fab")
			(effects
				(font
					(size 1.27 1.27)
				)
			)
		)
		(duplicate_pad_numbers_are_jumpers no)
		(fp_line
			(start -0.299974 0.150114)
			(end -0.299974 -0.150114)
			(stroke
				(width 0.1)
				(type default)
			)
			(layer "F.Fab")
		)
		(fp_line
			(start 0.299974 0.150114)
			(end -0.299974 0.150114)
			(stroke
				(width 0.1)
				(type default)
			)
			(layer "F.Fab")
		)
		(fp_line
			(start -0.299974 -0.150114)
			(end 0.299974 -0.150114)
			(stroke
				(width 0.1)
				(type default)
			)
			(layer "F.Fab")
		)
		(fp_line
			(start 0.299974 -0.150114)
			(end 0.299974 0.150114)
			(stroke
				(width 0.1)
				(type default)
			)
			(layer "F.Fab")
		)
		(pad "1" smd rect
			(at -0.2667 0 270)
			(size 0.3048 0.381)
			(layers "F.Cu" "F.Mask" "F.Paste")
			(net "P5E_CPU1_P0_TX_BUF_C_DP<4>")
		)
		(pad "2" smd rect
			(at 0.2667 0 270)
			(size 0.3048 0.381)
			(layers "F.Cu" "F.Mask" "F.Paste")
			(net "P5E_CPU1_P0_TX_BUF_DP<4>")
		)
	)
)
